(kicad_pcb
	(version 20221018)
	(generator pcbnew)
	(general
    (thickness 1.6)
  )
	(paper "A4")
	(title_block
    (title "NUC Computer Cluster Power Breakout HW")
    (date "2023-10-18")
    (rev "1.4.3")
    (company "Antmicro Ltd.")
		(comment 9 "footprints 178-183 of 234")
	)
	(layers
    (0 "F.Cu" mixed)
    (1 "In1.Cu" power)
    (2 "In2.Cu" mixed)
    (31 "B.Cu" power)
    (32 "B.Adhes" user "B.Adhesive")
    (33 "F.Adhes" user "F.Adhesive")
    (34 "B.Paste" user)
    (35 "F.Paste" user)
    (36 "B.SilkS" user "B.Silkscreen")
    (37 "F.SilkS" user "F.Silkscreen")
    (38 "B.Mask" user)
    (39 "F.Mask" user)
    (40 "Dwgs.User" user "User.Drawings")
    (41 "Cmts.User" user "User.Comments")
    (42 "Eco1.User" user "User.Eco1")
    (43 "Eco2.User" user "User.Eco2")
    (44 "Edge.Cuts" user)
    (45 "Margin" user)
    (46 "B.CrtYd" user "B.Courtyard")
    (47 "F.CrtYd" user "F.Courtyard")
    (48 "B.Fab" user)
    (49 "F.Fab" user)
  )
	(footprint "antmicro-footprints:C_0402_1005Metric" (layer "F.Cu")
    (at 165.1 123.5 90)
    (descr "Capacitor SMD 0402")
    (tags "capacitor SMD 0402")
    (property "Author" "Antmicro")
    (property "Dielectric" "X5R")
    (property "License" "Apache-2.0")
    (property "MPN" "GRM155R61H104KE14D")
    (property "Manufacturer" "Murata")
    (property "Sheetfile" "ftdi-module.kicad_sch")
    (property "Sheetname" "FTDI")
    (property "Val" "100n")
    (property "Voltage" "50V")
    (property "ki_description" "SMD Multilayer Ceramic Capacitor, 0.1 µF, 50 V, 0402 [1005 Metric], ± 10%, X5R, GRM Series")
    (property "ki_keywords" "0402, SMT, CAPACITOR, PASSIVE, CERAMIC, MLCC")
    (zone_connect 1)
    (attr smd)
    (fp_text reference "C9" (at -2.45 0.4 90) (layer "F.SilkS")
        (effects (font (size 0.7 0.7) (thickness 0.15)) (justify left bottom))
    )
    (fp_text value "C_100n_0402" (at -1.022927 2.155213 90) (layer "F.Fab")
        (effects (font (size 0.7 0.7) (thickness 0.15)) (justify left bottom))
    )
    (fp_text user "Author: Antmicro" (at -0.939 3.399 90) (layer "F.Fab") hide
        (effects (font (size 0.7 0.7) (thickness 0.15)) (justify left bottom))
    )
    (fp_text user "${REFERENCE}" (at -0.939 4.599 90) (layer "F.Fab") hide
        (effects (font (size 0.7 0.7) (thickness 0.15)) (justify left bottom))
    )
    (fp_text user "License: Apache-2.0" (at -0.939 5.799 90) (layer "F.Fab") hide
        (effects (font (size 0.7 0.7) (thickness 0.15)) (justify left bottom))
    )
    (fp_rect (start -0.925 -0.47) (end 0.925 0.47)
      (stroke (width 0.05) (type default)) (fill none) (layer "F.CrtYd"))
    (fp_line (start -0.494 -0.25) (end 0.504 -0.25)
      (stroke (width 0.15) (type solid)) (layer "F.Fab"))
    (fp_line (start -0.494 0.248) (end -0.494 -0.25)
      (stroke (width 0.15) (type solid)) (layer "F.Fab"))
    (fp_line (start 0.504 -0.25) (end 0.504 0.248)
      (stroke (width 0.15) (type solid)) (layer "F.Fab"))
    (fp_line (start 0.504 0.248) (end -0.494 0.248)
      (stroke (width 0.15) (type solid)) (layer "F.Fab"))
    (pad "1" smd roundrect (at -0.48 0 90) (size 0.59 0.64) (layers "F.Cu" "F.Paste" "F.Mask") (roundrect_rratio 0.25)
      (net 77 "GNDD") (pintype "passive"))
    (pad "2" smd roundrect (at 0.48 0 90) (size 0.59 0.64) (layers "F.Cu" "F.Paste" "F.Mask") (roundrect_rratio 0.25)
      (net 7 "1V8_FT") (pintype "passive"))
  )
	(footprint "antmicro-footprints:LED_0603_1608Metric_G" (layer "F.Cu")
    (at 110.8 53.65)
    (descr "LED SMD 0603 Green")
    (tags "LED SMD 0603 Green")
    (property "Author" "Antmicro")
    (property "Color" "Green")
    (property "License" "Apache-2.0")
    (property "MPN" "LG L29K-G2J1-24-Z")
    (property "Manufacturer" "OSRAM")
    (property "Sheetfile" "d1600e-psu-breakout-board.kicad_sch")
    (property "Sheetname" "")
    (property "ki_description" "LED, Green, SMD, 0603, 20 mA, 1.7 V, 570 nm")
    (property "ki_keywords" "SMT, DIODE, SEMICONDUCTOR, LED")
    (zone_connect 1)
    (attr smd)
    (fp_text reference "D3" (at -0.8 1.7) (layer "F.SilkS")
        (effects (font (size 0.7 0.7) (thickness 0.15)) (justify left bottom))
    )
    (fp_text value "LED_G_0603_LG_L29K-G2J1-24-Z" (at -0.001 1.599) (layer "F.Fab")
        (effects (font (size 0.7 0.7) (thickness 0.15)) (justify left bottom))
    )
    (fp_text user "${REFERENCE}" (at -1.4224 5.999) (layer "F.Fab") hide
        (effects (font (size 0.7 0.7) (thickness 0.15)) (justify left bottom))
    )
    (fp_text user "Author: Antmicro" (at -1.4224 4.799) (layer "F.Fab") hide
        (effects (font (size 0.7 0.7) (thickness 0.15)) (justify left bottom))
    )
    (fp_text user "License: Apache-2.0" (at -1.4224 3.599) (layer "F.Fab") hide
        (effects (font (size 0.7 0.7) (thickness 0.15)) (justify left bottom))
    )
    (fp_line (start -1.18 -0.319) (end -1.18 0.321)
      (stroke (width 0.15) (type solid)) (layer "F.SilkS"))
    (fp_line (start -0.094672 0.001008) (end -0.24 0.001008)
      (stroke (width 0.1) (type solid)) (layer "F.SilkS"))
    (fp_line (start -0.094672 0.001008) (end 0.105328 -0.198992)
      (stroke (width 0.1) (type solid)) (layer "F.SilkS"))
    (fp_line (start -0.094672 0.201008) (end -0.094672 -0.198992)
      (stroke (width 0.1) (type solid)) (layer "F.SilkS"))
    (fp_line (start 0.105328 0.001008) (end 0.24 0.001)
      (stroke (width 0.1) (type solid)) (layer "F.SilkS"))
    (fp_line (start 0.105328 0.201008) (end -0.094672 0.001008)
      (stroke (width 0.1) (type solid)) (layer "F.SilkS"))
    (fp_line (start 0.105328 0.201008) (end 0.105328 -0.198992)
      (stroke (width 0.1) (type solid)) (layer "F.SilkS"))
    (fp_line (start 0.22 -0.35) (end -0.22 -0.35)
      (stroke (width 0.15) (type solid)) (layer "F.SilkS"))
    (fp_line (start 0.22 0.35) (end -0.22 0.35)
      (stroke (width 0.15) (type solid)) (layer "F.SilkS"))
    (fp_rect (start 1.25 0.65) (end -1.25 -0.65)
      (stroke (width 0.05) (type solid)) (fill none) (layer "F.CrtYd"))
    (fp_line (start -0.199 -0.202) (end -0.199 0.1)
      (stroke (width 0.15) (type solid)) (layer "F.Fab"))
    (fp_line (start -0.199 0) (end -0.597 0)
      (stroke (width 0.15) (type solid)) (layer "F.Fab"))
    (fp_line (start -0.199 0.2) (end -0.199 0.1)
      (stroke (width 0.15) (type solid)) (layer "F.Fab"))
    (fp_line (start -0.101 0) (end 0.201 0.2)
      (stroke (width 0.15) (type solid)) (layer "F.Fab"))
    (fp_line (start 0.201 -0.202) (end -0.101 0)
      (stroke (width 0.15) (type solid)) (layer "F.Fab"))
    (fp_line (start 0.201 0) (end 0.201 -0.202)
      (stroke (width 0.15) (type solid)) (layer "F.Fab"))
    (fp_line (start 0.201 0.2) (end 0.201 0)
      (stroke (width 0.15) (type solid)) (layer "F.Fab"))
    (fp_line (start 0.599 0) (end 0.201 0)
      (stroke (width 0.15) (type solid)) (layer "F.Fab"))
    (fp_rect (start 0.848 0.4) (end -0.85 -0.402)
      (stroke (width 0.15) (type solid)) (fill none) (layer "F.Fab"))
    (pad "1" smd roundrect (at -0.7 0 180) (size 0.8 1) (layers "F.Cu" "F.Paste" "F.Mask") (roundrect_rratio 0.2)
      (net 4 "GND") (pinfunction "C") (pintype "passive"))
    (pad "2" smd roundrect (at 0.7 0 180) (size 0.8 1) (layers "F.Cu" "F.Paste" "F.Mask") (roundrect_rratio 0.2)
      (net 36 "Net-(D3-A)") (pinfunction "A") (pintype "passive"))
  )
	(footprint "antmicro-footprints:Vishay_PowerPAK_1212-8_Single" (layer "F.Cu")
    (at 120.25 86.1 90)
    (descr "PowerPAK 1212-8 Single")
    (tags "Vishay PowerPAK 1212-8 Single")
    (property "Author" "Antmicro")
    (property "License" "Apache-2.0")
    (property "MPN" "SI7613DN-T1-GE3")
    (property "Manufacturer" "Vishay")
    (property "Sheetfile" "power-switch.kicad_sch")
    (property "Sheetname" "Power switch 1")
    (property "ki_description" "Power MOSFET, P Channel, 20 V, 35 A, 0.0072 ohm, PowerPAK 1212, Surface Mount")
    (property "ki_keywords" "SMT, TRANSISTOR, SEMICONDUCTOR, MOSFET, PMOS")
    (attr smd)
    (fp_text reference "QA1" (at -2.85 0.5 180) (layer "F.SilkS")
        (effects (font (size 0.7 0.7) (thickness 0.15)) (justify left bottom))
    )
    (fp_text value "SI7613DN-T1-GE3" (at 0 2.7 90) (layer "F.Fab")
        (effects (font (size 0.7 0.7) (thickness 0.15)) (justify left bottom))
    )
    (fp_text user "Author: Antmicro" (at -8 5.9 90) (layer "F.Fab") hide
        (effects (font (size 0.7 0.7) (thickness 0.15)) (justify left bottom))
    )
    (fp_text user "License: Apache-2.0" (at -8 7.1 90) (layer "F.Fab") hide
        (effects (font (size 0.7 0.7) (thickness 0.15)) (justify left bottom))
    )
    (fp_text user "${REFERENCE}" (at -8 4.7 90) (layer "F.Fab") hide
        (effects (font (size 0.7 0.7) (thickness 0.15)) (justify left bottom))
    )
    (fp_line (start -1.651 -1.651) (end -1.651 -1.317)
      (stroke (width 0.15) (type solid)) (layer "F.SilkS"))
    (fp_line (start -1.651 -1.651) (end 1.648 -1.651)
      (stroke (width 0.15) (type solid)) (layer "F.SilkS"))
    (fp_line (start -1.635 1.3) (end -1.635 1.634)
      (stroke (width 0.15) (type solid)) (layer "F.SilkS"))
    (fp_line (start -1.635 1.634) (end 1.634 1.634)
      (stroke (width 0.15) (type solid)) (layer "F.SilkS"))
    (fp_line (start 1.634 1.3) (end 1.634 1.634)
      (stroke (width 0.15) (type solid)) (layer "F.SilkS"))
    (fp_line (start 1.648 -1.651) (end 1.648 -1.317)
      (stroke (width 0.15) (type solid)) (layer "F.SilkS"))
    (fp_circle (center -1.9 -1.4) (end -1.85 -1.4)
      (stroke (width 0.15) (type solid)) (fill solid) (layer "F.SilkS"))
    (fp_rect (start -2 -1.8) (end 2 1.798)
      (stroke (width 0.05) (type solid)) (fill none) (layer "F.CrtYd"))
    (fp_line (start -1.6425 -1.4175) (end -1.4175 -1.6425)
      (stroke (width 0.15) (type solid)) (layer "F.Fab"))
    (fp_rect (start -1.651 -1.651) (end 1.648 1.648)
      (stroke (width 0.15) (type solid)) (fill none) (layer "F.Fab"))
    (pad "1" smd rect (at -1.436 -0.99 90) (size 0.99 0.405) (layers "F.Cu" "F.Paste" "F.Mask")
      (net 11 "VCC12V0") (pinfunction "S") (pintype "passive"))
    (pad "2" smd rect (at -1.436 -0.332 90) (size 0.99 0.405) (layers "F.Cu" "F.Paste" "F.Mask")
      (net 11 "VCC12V0") (pinfunction "S") (pintype "passive"))
    (pad "3" smd rect (at -1.436 0.33 90) (size 0.99 0.405) (layers "F.Cu" "F.Paste" "F.Mask")
      (net 11 "VCC12V0") (pinfunction "S") (pintype "passive"))
    (pad "4" smd rect (at -1.436 0.988 90) (size 0.99 0.405) (layers "F.Cu" "F.Paste" "F.Mask")
      (net 93 "Net-(QA1-G)") (pinfunction "G") (pintype "passive"))
    (pad "5" smd custom (at 0.557 0 90) (size 1.725 2.235) (layers "F.Cu" "F.Paste" "F.Mask")
      (net 21 "C_MEAS_1") (pinfunction "D") (pintype "passive") (zone_connect 2)
      (options (clearance outline) (anchor rect))
      (primitives
        (gr_poly
          (pts
            (xy 0.8625 0.1275)
            (xy 0.8625 -0.1275)
            (xy 1.3725 -0.1275)
            (xy 1.3725 -0.5325)
            (xy 0.8625 -0.5325)
            (xy 0.8625 -0.7875)
            (xy 1.3725 -0.7875)
            (xy 1.3725 -1.195)
            (xy 0.6125 -1.195)
            (xy 0.6125 1.195)
            (xy 1.3725 1.195)
            (xy 1.3725 0.7875)
            (xy 0.8625 0.7875)
            (xy 0.8625 0.5325)
            (xy 1.3725 0.5325)
            (xy 1.3725 0.1275)
          )
          (width 0) (fill yes))
      ))
  )
	(footprint "antmicro-footprints:R_0402_1005Metric" (layer "F.Cu")
    (at 154.6 91.8 -90)
    (descr "Resistor SMD 0402")
    (tags "resistor SMD 0402")
    (property "Author" "Antmicro")
    (property "License" "Apache-2.0")
    (property "MPN" "CR0402-FX-2R00GLF")
    (property "Manufacturer" "Bourns")
    (property "Sheetfile" "power-switch.kicad_sch")
    (property "Sheetname" "Power switch 3")
    (property "Tolerance" "1%")
    (property "Val" "2R")
    (property "ki_description" "SMD Chip Resistor")
    (property "ki_keywords" "0402, SMT, RESISTOR, PASSIVE")
    (attr smd)
    (fp_text reference "R65" (at 1.75 -0.05 -180) (layer "F.SilkS")
        (effects (font (size 0.7 0.7) (thickness 0.15)) (justify right bottom))
    )
    (fp_text value "R_2R_0402" (at -1.011843 1.772047 90) (layer "F.Fab")
        (effects (font (size 0.7 0.7) (thickness 0.15)) (justify right bottom))
    )
    (fp_text user "${REFERENCE}" (at -0.95 3.168 90) (layer "F.Fab") hide
        (effects (font (size 0.7 0.7) (thickness 0.15)) (justify right bottom))
    )
    (fp_text user "License: Apache-2.0" (at -0.95 5.169 90) (layer "F.Fab") hide
        (effects (font (size 0.7 0.7) (thickness 0.15)) (justify right bottom))
    )
    (fp_text user "Author: Antmicro" (at -0.95 4.169 90) (layer "F.Fab") hide
        (effects (font (size 0.7 0.7) (thickness 0.15)) (justify right bottom))
    )
    (fp_rect (start -0.925 -0.47) (end 0.925 0.47)
      (stroke (width 0.05) (type default)) (fill none) (layer "F.CrtYd"))
    (fp_rect (start -0.5 -0.25) (end 0.5 0.25)
      (stroke (width 0.15) (type solid)) (fill none) (layer "F.Fab"))
    (pad "1" smd roundrect (at -0.48 0 270) (size 0.59 0.64) (layers "F.Cu" "F.Paste" "F.Mask") (roundrect_rratio 0.25)
      (net 101 "Net-(QB3-G)") (pintype "passive"))
    (pad "2" smd roundrect (at 0.48 0 270) (size 0.59 0.64) (layers "F.Cu" "F.Paste" "F.Mask") (roundrect_rratio 0.25)
      (net 86 "Net-(D18-A)") (pintype "passive"))
  )
	(footprint "antmicro-footprints:R_0402_1005Metric" (layer "F.Cu")
    (at 184.3 118.75 90)
    (descr "Resistor SMD 0402")
    (tags "resistor SMD 0402")
    (property "Author" "Antmicro")
    (property "License" "Apache-2.0")
    (property "MPN" "CR0402-FX-5101GLF")
    (property "Manufacturer" "Bourns")
    (property "Sheetfile" "ftdi-module.kicad_sch")
    (property "Sheetname" "FTDI")
    (property "Tolerance" "1%")
    (property "Val" "5k1")
    (property "ki_description" "SMD Chip Resistor, 5.1 kohm, ± 1%, 63 mW, 0402 [1005 Metric], Thick Film, General Purpose")
    (property "ki_keywords" "0402, SMT, RESISTOR, PASSIVE")
    (attr smd)
    (fp_text reference "R57" (at -0.95 -0.6 90) (layer "F.SilkS")
        (effects (font (size 0.7 0.7) (thickness 0.15)) (justify left bottom))
    )
    (fp_text value "R_5k1_0402" (at -1.011843 1.772047 90) (layer "F.Fab")
        (effects (font (size 0.7 0.7) (thickness 0.15)) (justify left bottom))
    )
    (fp_text user "${REFERENCE}" (at -0.95 3.168 90) (layer "F.Fab") hide
        (effects (font (size 0.7 0.7) (thickness 0.15)) (justify left bottom))
    )
    (fp_text user "License: Apache-2.0" (at -0.95 5.169 90) (layer "F.Fab") hide
        (effects (font (size 0.7 0.7) (thickness 0.15)) (justify left bottom))
    )
    (fp_text user "Author: Antmicro" (at -0.95 4.169 90) (layer "F.Fab") hide
        (effects (font (size 0.7 0.7) (thickness 0.15)) (justify left bottom))
    )
    (fp_rect (start -0.925 -0.47) (end 0.925 0.47)
      (stroke (width 0.05) (type default)) (fill none) (layer "F.CrtYd"))
    (fp_rect (start -0.5 -0.25) (end 0.5 0.25)
      (stroke (width 0.15) (type solid)) (fill none) (layer "F.Fab"))
    (pad "1" smd roundrect (at -0.48 0 90) (size 0.59 0.64) (layers "F.Cu" "F.Paste" "F.Mask") (roundrect_rratio 0.25)
      (net 77 "GNDD") (pintype "passive"))
    (pad "2" smd roundrect (at 0.48 0 90) (size 0.59 0.64) (layers "F.Cu" "F.Paste" "F.Mask") (roundrect_rratio 0.25)
      (net 113 "Net-(U1-CC_{1})") (pintype "passive"))
  )
	(footprint "antmicro-footprints:PCM12SMTR" (layer "F.Cu")
    (at 91.8 135.751 -90)
    (property "Author" "Antmicro")
    (property "License" "Apache-2.0")
    (property "MPN" "PCM12SMTR")
    (property "Manufacturer" "C&K")
    (property "Sheetfile" "d1600e-psu-breakout-board.kicad_sch")
    (property "Sheetname" "")
    (property "ki_description" "Slide switch")
    (property "ki_keywords" "VERTICAL, SMT, SWITCH, SWITCH, SLIDE")
    (attr smd)
    (fp_text reference "S1" (at 1.474 -3.65 90) (layer "F.SilkS")
        (effects (font (size 0.7 0.7) (thickness 0.15)) (justify right bottom))
    )
    (fp_text value "SW_SPDT_PCM12SMTR" (at 0 4.15 90) (layer "F.Fab")
        (effects (font (size 0.7 0.7) (thickness 0.15)) (justify right bottom))
    )
    (fp_text user "${REFERENCE}" (at -2.152 7.94 90) (layer "F.Fab") hide
        (effects (font (size 0.7 0.7) (thickness 0.15)) (justify right bottom))
    )
    (fp_text user "License: Apache-2.0" (at -2.152 10.339 90) (layer "F.Fab") hide
        (effects (font (size 0.7 0.7) (thickness 0.15)) (justify right bottom))
    )
    (fp_text user "Author: Antmicro" (at -2.152 9.14 90) (layer "F.Fab") hide
        (effects (font (size 0.7 0.7) (thickness 0.15)) (justify right bottom))
    )
    (fp_line (start -3.351 0.348) (end -3.351 -0.251)
      (stroke (width 0.15) (type solid)) (layer "F.SilkS"))
    (fp_line (start -2.901 1.348) (end 2.9 1.348)
      (stroke (width 0.15) (type solid)) (layer "F.SilkS"))
    (fp_line (start -1.601 -1.251) (end 0.1 -1.251)
      (stroke (width 0.15) (type solid)) (layer "F.SilkS"))
    (fp_line (start 3.349 -0.251) (end 3.349 0.348)
      (stroke (width 0.15) (type solid)) (layer "F.SilkS"))
    (fp_circle (center -3.15 -2.45) (end -3.1 -2.39)
      (stroke (width 0.15) (type solid)) (fill solid) (layer "F.SilkS"))
    (fp_line (start -4.42 -1.57) (end -2.86 -1.57)
      (stroke (width 0.05) (type solid)) (layer "F.CrtYd"))
    (fp_line (start -4.42 1.65) (end -4.42 -1.57)
      (stroke (width 0.05) (type solid)) (layer "F.CrtYd"))
    (fp_line (start -2.86 -2.7) (end 2.83 -2.7)
      (stroke (width 0.05) (type solid)) (layer "F.CrtYd"))
    (fp_line (start -2.86 -1.57) (end -2.86 -2.7)
      (stroke (width 0.05) (type solid)) (layer "F.CrtYd"))
    (fp_line (start -1.77 1.65) (end -4.42 1.65)
      (stroke (width 0.05) (type solid)) (layer "F.CrtYd"))
    (fp_line (start -1.77 3.08) (end -1.77 1.65)
      (stroke (width 0.05) (type solid)) (layer "F.CrtYd"))
    (fp_line (start 1.74 1.65) (end 1.74 3.08)
      (stroke (width 0.05) (type solid)) (layer "F.CrtYd"))
    (fp_line (start 1.74 3.08) (end -1.77 3.08)
      (stroke (width 0.05) (type solid)) (layer "F.CrtYd"))
    (fp_line (start 2.83 -2.7) (end 2.83 -1.57)
      (stroke (width 0.05) (type solid)) (layer "F.CrtYd"))
    (fp_line (start 2.83 -1.57) (end 4.4 -1.57)
      (stroke (width 0.05) (type solid)) (layer "F.CrtYd"))
    (fp_line (start 4.4 -1.57) (end 4.4 1.65)
      (stroke (width 0.05) (type solid)) (layer "F.CrtYd"))
    (fp_line (start 4.4 1.65) (end 1.74 1.65)
      (stroke (width 0.05) (type solid)) (layer "F.CrtYd"))
    (fp_line (start -3.351 -1.251) (end 3.349 -1.251)
      (stroke (width 0.15) (type solid)) (layer "F.Fab"))
    (fp_line (start -3.351 1.348) (end -3.351 -1.251)
      (stroke (width 0.15) (type solid)) (layer "F.Fab"))
    (fp_line (start -1.502 1.348) (end -3.351 1.348)
      (stroke (width 0.15) (type solid)) (layer "F.Fab"))
    (fp_line (start -1.502 1.348) (end -1.502 2.849)
      (stroke (width 0.15) (type solid)) (layer "F.Fab"))
    (fp_line (start -1.502 2.849) (end 1.499 2.849)
      (stroke (width 0.15) (type solid)) (layer "F.Fab"))
    (fp_line (start 1.499 1.348) (end -1.502 1.348)
      (stroke (width 0.15) (type solid)) (layer "F.Fab"))
    (fp_line (start 1.499 2.849) (end 1.499 1.348)
      (stroke (width 0.15) (type solid)) (layer "F.Fab"))
    (fp_line (start 3.349 -1.251) (end 3.349 1.348)
      (stroke (width 0.15) (type solid)) (layer "F.Fab"))
    (fp_line (start 3.349 1.348) (end 1.499 1.348)
      (stroke (width 0.15) (type solid)) (layer "F.Fab"))
    (pad "" np_thru_hole circle (at -1.502 0.049 270) (size 0.9 0.9) (drill 0.9) (layers "*.Cu" "*.Mask"))
    (pad "" np_thru_hole circle (at 1.499 0.049 270) (size 0.9 0.9) (drill 0.9) (layers "*.Cu" "*.Mask"))
    (pad "1" smd roundrect (at -2.25 -1.7 270) (size 0.7 1.5) (layers "F.Cu" "F.Paste" "F.Mask") (roundrect_rratio 0.25)
      (net 166 "unconnected-(S1-Pad1)") (pintype "passive+no_connect"))
    (pad "2" smd roundrect (at 0.749 -1.7 270) (size 0.7 1.5) (layers "F.Cu" "F.Paste" "F.Mask") (roundrect_rratio 0.25)
      (net 51 "PSU_ON") (pintype "passive"))
    (pad "3" smd roundrect (at 2.248 -1.7 270) (size 0.7 1.5) (layers "F.Cu" "F.Paste" "F.Mask") (roundrect_rratio 0.25)
      (net 4 "GND") (pintype "passive"))
    (pad "S1" smd roundrect (at -3.651 -0.915 270) (size 1 0.8) (layers "F.Cu" "F.Paste" "F.Mask") (roundrect_rratio 0.25)
      (net 167 "unconnected-(S1-SH-PadS1)") (pinfunction "SH") (pintype "passive+no_connect"))
    (pad "S2" smd roundrect (at -3.651 1.013 270) (size 1 0.8) (layers "F.Cu" "F.Paste" "F.Mask") (roundrect_rratio 0.25)
      (net 167 "unconnected-(S1-SH-PadS1)") (pinfunction "SH") (pintype "passive+no_connect"))
    (pad "S3" smd roundrect (at 3.65 1.013 270) (size 1 0.8) (layers "F.Cu" "F.Paste" "F.Mask") (roundrect_rratio 0.25)
      (net 167 "unconnected-(S1-SH-PadS1)") (pinfunction "SH") (pintype "passive+no_connect"))
    (pad "S4" smd roundrect (at 3.65 -0.915 270) (size 1 0.8) (layers "F.Cu" "F.Paste" "F.Mask") (roundrect_rratio 0.25)
      (net 167 "unconnected-(S1-SH-PadS1)") (pinfunction "SH") (pintype "passive+no_connect"))
  )
)
